# S9S_MB_2U (Grand Teton) — schematic netlist excerpt (pin names and nets, part order shuffled) for the footprints in the layout excerpt that follows; sources: Cadence DE-HDL packaged netlist, KiCad conversion of 03242023_DA0F0TMBIJ0_F0T_Motherboard_J_brd_V01_OCP.brd

R4062  Q_RES  0 5% EMPTY  pkg 0402LF  page 242 : A = P12V_SCM_EN ; B = P12V_SCM_EN_R
R2402  Q_RES  0 5% CHIP  pkg 0402LF  page 278 : A = SMB_VR_3V3AUX_SCL_R2 ; B = SMB_CLK_PVCCD_HV_CPU0

(kicad_pcb
	(version 20260206)
	(generator "pcbnew")
	(generator_version "10.0")
	(general
		(thickness 1.6)
		(legacy_teardrops no)
	)
	(paper "A4")
	(title_block
		(title "03242023_DA0F0TMBIJ0_F0T_Motherboard_J_brd_V01_OCP.brd")
		(comment 1 "Grand Teton / footprints 2447-2448 of 6105")
	)
	(layers
		(0 "F.Cu" signal "TOP")
		(4 "In1.Cu" signal "GND")
		(6 "In2.Cu" signal "IN1")
		(8 "In3.Cu" signal "GND1")
		(10 "In4.Cu" signal "IN2")
		(12 "In5.Cu" signal "GND2")
		(14 "In6.Cu" signal "IN3")
		(16 "In7.Cu" signal "GND3")
		(18 "In8.Cu" signal "VCC")
		(20 "In9.Cu" signal "VCC1")
		(22 "In10.Cu" signal "GND4")
		(24 "In11.Cu" signal "IN4")
		(26 "In12.Cu" signal "GND5")
		(28 "In13.Cu" signal "IN5")
		(30 "In14.Cu" signal "GND6")
		(32 "In15.Cu" signal "IN6")
		(34 "In16.Cu" signal "GND7")
		(2 "B.Cu" signal "BOTTOM")
		(9 "F.Adhes" user "F.Adhesive")
		(11 "B.Adhes" user "B.Adhesive")
		(13 "F.Paste" user "Package Geometry/Pastemask Top")
		(15 "B.Paste" user "Package Geometry/Pastemask Bottom")
		(5 "F.SilkS" user "Ref Des/Silkscreen Top")
		(7 "B.SilkS" user "Ref Des/Silkscreen Bottom")
		(1 "F.Mask" user "Board Geometry/Soldermask Top")
		(3 "B.Mask" user "Board Geometry/Soldermask Bottom")
		(17 "Dwgs.User" user "User.Drawings")
		(19 "Cmts.User" user "User.Comments")
		(21 "Eco1.User" user "User.Eco1")
		(23 "Eco2.User" user "User.Eco2")
		(25 "Edge.Cuts" user "Board Geometry/Outline")
		(27 "Margin" user)
		(31 "F.CrtYd" user "Package Geometry/Place Bound Top")
		(29 "B.CrtYd" user "Package Geometry/Place Bound Bottom")
		(35 "F.Fab" user "Ref Des/Assembly Top")
		(33 "B.Fab" user "Ref Des/Assembly Bottom")
	)
	(footprint ""
		(layer "F.Cu")
		(at 435.350158 -118.568216 90)
		(property "Reference" "R2402"
			(at 0 0 90)
			(layer "F.SilkS")
			(hide yes)
			(effects
				(font
					(size 1.27 1.27)
				)
			)
		)
		(property "Value" ""
			(at 0 0 90)
			(layer "F.Fab")
			(effects
				(font
					(size 1.27 1.27)
				)
			)
		)
		(duplicate_pad_numbers_are_jumpers no)
		(fp_line
			(start 0.7874 -0.4064)
			(end 0.7874 0.4064)
			(stroke
				(width 0.1524)
				(type default)
			)
			(layer "F.SilkS")
		)
		(fp_line
			(start -0.7874 -0.4064)
			(end 0.7874 -0.4064)
			(stroke
				(width 0.1524)
				(type default)
			)
			(layer "F.SilkS")
		)
		(fp_line
			(start 0.7874 0.4064)
			(end -0.7874 0.4064)
			(stroke
				(width 0.1524)
				(type default)
			)
			(layer "F.SilkS")
		)
		(fp_line
			(start -0.7874 0.4064)
			(end -0.7874 -0.4064)
			(stroke
				(width 0.1524)
				(type default)
			)
			(layer "F.SilkS")
		)
		(fp_line
			(start -0.12065 -0.305054)
			(end -0.12065 -0.2794)
			(stroke
				(width 0.1)
				(type default)
			)
			(layer "F.Fab")
		)
		(fp_line
			(start -0.67945 -0.305054)
			(end -0.12065 -0.305054)
			(stroke
				(width 0.1)
				(type default)
			)
			(layer "F.Fab")
		)
		(fp_line
			(start 0.67945 -0.3048)
			(end 0.67945 0.3048)
			(stroke
				(width 0.1)
				(type default)
			)
			(layer "F.Fab")
		)
		(fp_line
			(start 0.12065 -0.3048)
			(end 0.67945 -0.3048)
			(stroke
				(width 0.1)
				(type default)
			)
			(layer "F.Fab")
		)
		(fp_line
			(start 0.12065 -0.2794)
			(end 0.12065 -0.3048)
			(stroke
				(width 0.1)
				(type default)
			)
			(layer "F.Fab")
		)
		(fp_line
			(start -0.12065 -0.2794)
			(end 0.12065 -0.2794)
			(stroke
				(width 0.1)
				(type default)
			)
			(layer "F.Fab")
		)
		(fp_line
			(start 0.120396 0.2794)
			(end -0.12065 0.2794)
			(stroke
				(width 0.1)
				(type default)
			)
			(layer "F.Fab")
		)
		(fp_line
			(start -0.12065 0.2794)
			(end -0.12065 0.3048)
			(stroke
				(width 0.1)
				(type default)
			)
			(layer "F.Fab")
		)
		(fp_line
			(start 0.67945 0.3048)
			(end 0.120396 0.3048)
			(stroke
				(width 0.1)
				(type default)
			)
			(layer "F.Fab")
		)
		(fp_line
			(start 0.120396 0.3048)
			(end 0.120396 0.2794)
			(stroke
				(width 0.1)
				(type default)
			)
			(layer "F.Fab")
		)
		(fp_line
			(start -0.12065 0.3048)
			(end -0.67945 0.3048)
			(stroke
				(width 0.1)
				(type default)
			)
			(layer "F.Fab")
		)
		(fp_line
			(start -0.67945 0.3048)
			(end -0.67945 -0.305054)
			(stroke
				(width 0.1)
				(type default)
			)
			(layer "F.Fab")
		)
		(pad "1" smd circle
			(at -0.40005 0 90)
			(size 0 0)
			(layers "F.Cu" "F.Mask" "F.Paste")
			(net "SMB_VR_3V3AUX_SCL_R2")
		)
		(pad "2" smd circle
			(at 0.40005 0 90)
			(size 0 0)
			(layers "F.Cu" "F.Mask" "F.Paste")
			(net "SMB_CLK_PVCCD_HV_CPU0")
		)
	)
	(footprint ""
		(layer "F.Cu")
		(at 197.21068 -41.466516 180)
		(property "Reference" "R4062"
			(at 0 0 180)
			(layer "F.SilkS")
			(hide yes)
			(effects
				(font
					(size 1.27 1.27)
				)
			)
		)
		(property "Value" ""
			(at 0 0 180)
			(layer "F.Fab")
			(effects
				(font
					(size 1.27 1.27)
				)
			)
		)
		(duplicate_pad_numbers_are_jumpers no)
		(fp_line
			(start 0.7874 0.4064)
			(end -0.7874 0.4064)
			(stroke
				(width 0.1524)
				(type default)
			)
			(layer "F.SilkS")
		)
		(fp_line
			(start 0.7874 -0.4064)
			(end 0.7874 0.4064)
			(stroke
				(width 0.1524)
				(type default)
			)
			(layer "F.SilkS")
		)
		(fp_line
			(start -0.7874 0.4064)
			(end -0.7874 -0.4064)
			(stroke
				(width 0.1524)
				(type default)
			)
			(layer "F.SilkS")
		)
		(fp_line
			(start -0.7874 -0.4064)
			(end 0.7874 -0.4064)
			(stroke
				(width 0.1524)
				(type default)
			)
			(layer "F.SilkS")
		)
		(fp_line
			(start 0.67945 0.3048)
			(end 0.120396 0.3048)
			(stroke
				(width 0.1)
				(type default)
			)
			(layer "F.Fab")
		)
		(fp_line
			(start 0.67945 -0.3048)
			(end 0.67945 0.3048)
			(stroke
				(width 0.1)
				(type default)
			)
			(layer "F.Fab")
		)
		(fp_line
			(start 0.12065 -0.2794)
			(end 0.12065 -0.3048)
			(stroke
				(width 0.1)
				(type default)
			)
			(layer "F.Fab")
		)
		(fp_line
			(start 0.12065 -0.3048)
			(end 0.67945 -0.3048)
			(stroke
				(width 0.1)
				(type default)
			)
			(layer "F.Fab")
		)
		(fp_line
			(start 0.120396 0.3048)
			(end 0.120396 0.2794)
			(stroke
				(width 0.1)
				(type default)
			)
			(layer "F.Fab")
		)
		(fp_line
			(start 0.120396 0.2794)
			(end -0.12065 0.2794)
			(stroke
				(width 0.1)
				(type default)
			)
			(layer "F.Fab")
		)
		(fp_line
			(start -0.12065 0.3048)
			(end -0.67945 0.3048)
			(stroke
				(width 0.1)
				(type default)
			)
			(layer "F.Fab")
		)
		(fp_line
			(start -0.12065 0.2794)
			(end -0.12065 0.3048)
			(stroke
				(width 0.1)
				(type default)
			)
			(layer "F.Fab")
		)
		(fp_line
			(start -0.12065 -0.2794)
			(end 0.12065 -0.2794)
			(stroke
				(width 0.1)
				(type default)
			)
			(layer "F.Fab")
		)
		(fp_line
			(start -0.12065 -0.305054)
			(end -0.12065 -0.2794)
			(stroke
				(width 0.1)
				(type default)
			)
			(layer "F.Fab")
		)
		(fp_line
			(start -0.67945 0.3048)
			(end -0.67945 -0.305054)
			(stroke
				(width 0.1)
				(type default)
			)
			(layer "F.Fab")
		)
		(fp_line
			(start -0.67945 -0.305054)
			(end -0.12065 -0.305054)
			(stroke
				(width 0.1)
				(type default)
			)
			(layer "F.Fab")
		)
		(pad "1" smd circle
			(at -0.40005 0 180)
			(size 0 0)
			(layers "F.Cu" "F.Mask" "F.Paste")
			(net "P12V_SCM_EN")
		)
		(pad "2" smd circle
			(at 0.40005 0 180)
			(size 0 0)
			(layers "F.Cu" "F.Mask" "F.Paste")
			(net "P12V_SCM_EN_R")
		)
	)
)
